(kicad_pcb
	(version 20260206)
	(generator "pcbnew")
	(generator_version "10.0")
	(general
		(thickness 1.6)
		(legacy_teardrops no)
	)
	(paper "A4")
	(title_block
		(title "Wiwynn_Tioga_Pass_MB.brd")
		(comment 1 "Tioga Pass / footprints 1261-1267 of 4770")
	)
	(layers
		(0 "F.Cu" signal "TOP")
		(4 "In1.Cu" signal "L2GND")
		(6 "In2.Cu" signal "L3")
		(8 "In3.Cu" signal "L4GND")
		(10 "In4.Cu" signal "L5")
		(12 "In5.Cu" signal "L6GND")
		(14 "In6.Cu" signal "L7VCC")
		(16 "In7.Cu" signal "L8VCC")
		(18 "In8.Cu" signal "L9GND")
		(20 "In9.Cu" signal "L10")
		(22 "In10.Cu" signal "L11GND")
		(24 "In11.Cu" signal "L12")
		(26 "In12.Cu" signal "L13GND")
		(2 "B.Cu" signal "BOTTOM")
		(9 "F.Adhes" user "F.Adhesive")
		(11 "B.Adhes" user "B.Adhesive")
		(13 "F.Paste" user "Package Geometry/Pastemask Top")
		(15 "B.Paste" user "Package Geometry/Pastemask Bottom")
		(5 "F.SilkS" user "Ref Des/Silkscreen Top")
		(7 "B.SilkS" user "Ref Des/Silkscreen Bottom")
		(1 "F.Mask" user "Board Geometry/Soldermask Top")
		(3 "B.Mask" user "Board Geometry/Soldermask Bottom")
		(17 "Dwgs.User" user "User.Drawings")
		(19 "Cmts.User" user "User.Comments")
		(21 "Eco1.User" user "User.Eco1")
		(23 "Eco2.User" user "User.Eco2")
		(25 "Edge.Cuts" user "Board Geometry/Outline")
		(27 "Margin" user)
		(31 "F.CrtYd" user "Package Geometry/Place Bound Top")
		(29 "B.CrtYd" user "Package Geometry/Place Bound Bottom")
		(35 "F.Fab" user "Ref Des/Assembly Top")
		(33 "B.Fab" user "Ref Des/Assembly Bottom")
	)
	(footprint ""
		(layer "F.Cu")
		(at 163.592764 -70.694296 -90)
		(property "Reference" "R3D21"
			(at 0 0 270)
			(layer "F.SilkS")
			(hide yes)
			(effects
				(font
					(size 1.27 1.27)
				)
			)
		)
		(property "Value" ""
			(at 0 0 270)
			(layer "F.Fab")
			(effects
				(font
					(size 1.27 1.27)
				)
			)
		)
		(duplicate_pad_numbers_are_jumpers no)
		(fp_poly
			(pts
				(xy -0.2794 -0.1016) (xy 0.2794 -0.1016) (xy 0.2794 0.9906) (xy -0.2794 0.9906)
			)
			(stroke
				(width 0)
				(type default)
			)
			(fill no)
			(layer "F.CrtYd")
		)
		(fp_line
			(start -0.2794 0.9906)
			(end 0.2794 0.9906)
			(stroke
				(width 0.1)
				(type default)
			)
			(layer "F.Fab")
		)
		(fp_line
			(start 0.2794 0.9906)
			(end 0.2794 -0.1016)
			(stroke
				(width 0.1)
				(type default)
			)
			(layer "F.Fab")
		)
		(fp_line
			(start -0.2794 -0.1016)
			(end -0.2794 0.9906)
			(stroke
				(width 0.1)
				(type default)
			)
			(layer "F.Fab")
		)
		(fp_line
			(start 0.2794 -0.1016)
			(end -0.2794 -0.1016)
			(stroke
				(width 0.1)
				(type default)
			)
			(layer "F.Fab")
		)
		(pad "1" smd rect
			(at 0 0 270)
			(size 0.508 0.508)
			(layers "F.Cu" "F.Mask" "F.Paste")
			(net "PVDDQ_GHJ")
		)
		(pad "2" smd rect
			(at 0 0.889 270)
			(size 0.508 0.508)
			(layers "F.Cu" "F.Mask" "F.Paste")
			(net "PWRGD_CPU1_DRAMPWROK_GHJ_G")
		)
		(zone
			(layer "F.Cu")
			(hatch none 0.5)
			(connect_pads
				(clearance 0)
			)
			(min_thickness 0.25)
			(keepout
				(tracks not_allowed)
				(vias allowed)
				(pads allowed)
				(copperpour not_allowed)
				(footprints allowed)
			)
			(placement
				(enabled no)
				(sheetname "")
			)
			(fill
				(thermal_gap 0.5)
				(thermal_bridge_width 0.5)
				(island_removal_mode 0)
			)
			(polygon
				(pts
					(xy 162.957764 -70.948296) (xy 162.957764 -70.440296) (xy 163.338764 -70.440296) (xy 163.338764 -70.948296)
				)
			)
		)
		(zone
			(layer "F.Cu")
			(hatch none 0.5)
			(connect_pads
				(clearance 0)
			)
			(min_thickness 0.25)
			(keepout
				(tracks allowed)
				(vias not_allowed)
				(pads allowed)
				(copperpour not_allowed)
				(footprints allowed)
			)
			(placement
				(enabled no)
				(sheetname "")
			)
			(fill
				(thermal_gap 0.5)
				(thermal_bridge_width 0.5)
				(island_removal_mode 0)
			)
			(polygon
				(pts
					(xy 163.338764 -70.948296) (xy 163.338764 -70.440296) (xy 162.957764 -70.440296) (xy 162.957764 -70.948296)
				)
			)
		)
	)
	(footprint ""
		(layer "F.Cu")
		(at 398.768316 -157.664658 -90)
		(property "Reference" "RF23"
			(at -0.8382 -0.67818 270)
			(unlocked yes)
			(layer "F.SilkS")
			(effects
				(font
					(size 0.4064 0.254)
					(thickness 0.1524)
				)
				(justify left)
			)
		)
		(property "Value" ""
			(at 0 0 270)
			(layer "F.Fab")
			(effects
				(font
					(size 1.27 1.27)
				)
			)
		)
		(duplicate_pad_numbers_are_jumpers no)
		(fp_poly
			(pts
				(xy -0.2794 -0.1016) (xy 0.2794 -0.1016) (xy 0.2794 0.9906) (xy -0.2794 0.9906)
			)
			(stroke
				(width 0)
				(type default)
			)
			(fill no)
			(layer "F.CrtYd")
		)
		(fp_line
			(start -0.2794 0.9906)
			(end 0.2794 0.9906)
			(stroke
				(width 0.1)
				(type default)
			)
			(layer "F.Fab")
		)
		(fp_line
			(start 0.2794 0.9906)
			(end 0.2794 -0.1016)
			(stroke
				(width 0.1)
				(type default)
			)
			(layer "F.Fab")
		)
		(fp_line
			(start -0.2794 -0.1016)
			(end -0.2794 0.9906)
			(stroke
				(width 0.1)
				(type default)
			)
			(layer "F.Fab")
		)
		(fp_line
			(start 0.2794 -0.1016)
			(end -0.2794 -0.1016)
			(stroke
				(width 0.1)
				(type default)
			)
			(layer "F.Fab")
		)
		(pad "1" smd rect
			(at 0 0 270)
			(size 0.508 0.508)
			(layers "F.Cu" "F.Mask" "F.Paste")
			(net "VR_PVNN_PCH_AIREF1")
		)
		(pad "2" smd rect
			(at 0 0.889 270)
			(size 0.508 0.508)
			(layers "F.Cu" "F.Mask" "F.Paste")
			(net "ISENSE_PVNN_PCH_PH1_IMON")
		)
		(zone
			(layer "F.Cu")
			(hatch none 0.5)
			(connect_pads
				(clearance 0)
			)
			(min_thickness 0.25)
			(keepout
				(tracks not_allowed)
				(vias allowed)
				(pads allowed)
				(copperpour not_allowed)
				(footprints allowed)
			)
			(placement
				(enabled no)
				(sheetname "")
			)
			(fill
				(thermal_gap 0.5)
				(thermal_bridge_width 0.5)
				(island_removal_mode 0)
			)
			(polygon
				(pts
					(xy 398.133316 -157.918658) (xy 398.133316 -157.410658) (xy 398.514316 -157.410658) (xy 398.514316 -157.918658)
				)
			)
		)
		(zone
			(layer "F.Cu")
			(hatch none 0.5)
			(connect_pads
				(clearance 0)
			)
			(min_thickness 0.25)
			(keepout
				(tracks allowed)
				(vias not_allowed)
				(pads allowed)
				(copperpour not_allowed)
				(footprints allowed)
			)
			(placement
				(enabled no)
				(sheetname "")
			)
			(fill
				(thermal_gap 0.5)
				(thermal_bridge_width 0.5)
				(island_removal_mode 0)
			)
			(polygon
				(pts
					(xy 398.514316 -157.918658) (xy 398.514316 -157.410658) (xy 398.133316 -157.410658) (xy 398.133316 -157.918658)
				)
			)
		)
	)
	(footprint ""
		(layer "F.Cu")
		(at 210.312 -106.045)
		(property "Reference" ""
			(at 0 0 0)
			(layer "F.SilkS")
			(hide yes)
			(effects
				(font
					(size 1.27 1.27)
				)
			)
		)
		(property "Value" ""
			(at 0 0 0)
			(layer "F.Fab")
			(effects
				(font
					(size 1.27 1.27)
				)
			)
		)
		(duplicate_pad_numbers_are_jumpers no)
		(fp_poly
			(pts
				(arc
					(start 2.032 0)
					(mid -2.032 0)
					(end 2.032 0)
				)
			)
			(stroke
				(width 0)
				(type default)
			)
			(fill no)
			(layer "F.CrtYd")
		)
		(pad "1" smd circle
			(at 0 0)
			(size 1.016 1.016)
			(layers "F.Cu" "F.Mask" "F.Paste")
			(net "Net_394")
		)
		(zone
			(layer "F.Cu")
			(hatch none 0.5)
			(connect_pads
				(clearance 0)
			)
			(min_thickness 0.25)
			(keepout
				(tracks not_allowed)
				(vias allowed)
				(pads allowed)
				(copperpour not_allowed)
				(footprints allowed)
			)
			(placement
				(enabled no)
				(sheetname "")
			)
			(fill
				(thermal_gap 0.5)
				(thermal_bridge_width 0.5)
				(island_removal_mode 0)
			)
			(polygon
				(pts
					(arc
						(start 211.836 -106.045)
						(mid 208.788 -106.045)
						(end 211.836 -106.045)
					)
				)
			)
		)
		(zone
			(layers "F.Cu" "B.Cu" "In1.Cu" "In2.Cu" "In3.Cu" "In4.Cu" "In5.Cu" "In6.Cu"
				"In7.Cu" "In8.Cu" "In9.Cu" "In10.Cu" "In11.Cu" "In12.Cu"
			)
			(hatch none 0.5)
			(connect_pads
				(clearance 0)
			)
			(min_thickness 0.25)
			(keepout
				(tracks allowed)
				(vias not_allowed)
				(pads allowed)
				(copperpour not_allowed)
				(footprints allowed)
			)
			(placement
				(enabled no)
				(sheetname "")
			)
			(fill
				(thermal_gap 0.5)
				(thermal_bridge_width 0.5)
				(island_removal_mode 0)
			)
			(polygon
				(pts
					(arc
						(start 211.836 -106.045)
						(mid 208.788 -106.045)
						(end 211.836 -106.045)
					)
				)
			)
		)
	)
	(footprint ""
		(layer "F.Cu")
		(at 39.1414 -77.7494 -90)
		(property "Reference" "CT20"
			(at -0.8382 -0.67818 270)
			(unlocked yes)
			(layer "F.SilkS")
			(effects
				(font
					(size 0.4064 0.254)
					(thickness 0.1524)
				)
				(justify left)
			)
		)
		(property "Value" ""
			(at 0 0 270)
			(layer "F.Fab")
			(effects
				(font
					(size 1.27 1.27)
				)
			)
		)
		(duplicate_pad_numbers_are_jumpers no)
		(fp_poly
			(pts
				(xy 0.3048 -0.1016) (xy 0.3048 0.9906) (xy -0.3048 0.9906) (xy -0.3048 -0.1016)
			)
			(stroke
				(width 0)
				(type default)
			)
			(fill no)
			(layer "F.CrtYd")
		)
		(fp_line
			(start -0.3048 0.9906)
			(end 0.3048 0.9906)
			(stroke
				(width 0.1)
				(type default)
			)
			(layer "F.Fab")
		)
		(fp_line
			(start 0.3048 0.9906)
			(end 0.3048 -0.1016)
			(stroke
				(width 0.1)
				(type default)
			)
			(layer "F.Fab")
		)
		(fp_line
			(start -0.3048 -0.1016)
			(end -0.3048 0.9906)
			(stroke
				(width 0.1)
				(type default)
			)
			(layer "F.Fab")
		)
		(fp_line
			(start 0.3048 -0.1016)
			(end -0.3048 -0.1016)
			(stroke
				(width 0.1)
				(type default)
			)
			(layer "F.Fab")
		)
		(pad "1" smd rect
			(at 0 0 270)
			(size 0.508 0.508)
			(layers "F.Cu" "F.Mask" "F.Paste")
			(net "VR_PVCCIN_CPU1_PHASE4")
		)
		(pad "2" smd rect
			(at 0 0.889 270)
			(size 0.508 0.508)
			(layers "F.Cu" "F.Mask" "F.Paste")
			(net "VR_PVCCIN_CPU1_PHASE4_RC")
		)
		(zone
			(layer "F.Cu")
			(hatch none 0.5)
			(connect_pads
				(clearance 0)
			)
			(min_thickness 0.25)
			(keepout
				(tracks not_allowed)
				(vias allowed)
				(pads allowed)
				(copperpour not_allowed)
				(footprints allowed)
			)
			(placement
				(enabled no)
				(sheetname "")
			)
			(fill
				(thermal_gap 0.5)
				(thermal_bridge_width 0.5)
				(island_removal_mode 0)
			)
			(polygon
				(pts
					(xy 38.5064 -78.0034) (xy 38.5064 -77.4954) (xy 38.8874 -77.4954) (xy 38.8874 -78.0034)
				)
			)
		)
		(zone
			(layer "F.Cu")
			(hatch none 0.5)
			(connect_pads
				(clearance 0)
			)
			(min_thickness 0.25)
			(keepout
				(tracks allowed)
				(vias not_allowed)
				(pads allowed)
				(copperpour not_allowed)
				(footprints allowed)
			)
			(placement
				(enabled no)
				(sheetname "")
			)
			(fill
				(thermal_gap 0.5)
				(thermal_bridge_width 0.5)
				(island_removal_mode 0)
			)
			(polygon
				(pts
					(xy 38.8874 -78.0034) (xy 38.8874 -77.4954) (xy 38.5064 -77.4954) (xy 38.5064 -78.0034)
				)
			)
		)
	)
	(footprint ""
		(layer "F.Cu")
		(at 21.082 -62.9158 180)
		(property "Reference" "EU1E1"
			(at 2.921 5.25653 0)
			(unlocked yes)
			(layer "F.SilkS")
			(effects
				(font
					(size 0.7874 0.5842)
					(thickness 0.1524)
				)
			)
		)
		(property "Value" ""
			(at 0 0 180)
			(layer "F.Fab")
			(effects
				(font
					(size 1.27 1.27)
				)
			)
		)
		(duplicate_pad_numbers_are_jumpers no)
		(fp_line
			(start 4.8006 4.5593)
			(end 4.8006 4.445254)
			(stroke
				(width 0.1524)
				(type default)
			)
			(layer "F.SilkS")
		)
		(fp_line
			(start 4.8006 -0.7493)
			(end 4.8006 -0.635254)
			(stroke
				(width 0.1524)
				(type default)
			)
			(layer "F.SilkS")
		)
		(fp_line
			(start 0.4064 4.5593)
			(end 4.8006 4.5593)
			(stroke
				(width 0.1524)
				(type default)
			)
			(layer "F.SilkS")
		)
		(fp_line
			(start 0.4064 4.445254)
			(end 0.4064 4.5593)
			(stroke
				(width 0.1524)
				(type default)
			)
			(layer "F.SilkS")
		)
		(fp_line
			(start 0.4064 -0.635254)
			(end 0.4064 -0.7493)
			(stroke
				(width 0.1524)
				(type default)
			)
			(layer "F.SilkS")
		)
		(fp_line
			(start 0.4064 -0.7493)
			(end 4.8006 -0.7493)
			(stroke
				(width 0.1524)
				(type default)
			)
			(layer "F.SilkS")
		)
		(fp_circle
			(center -0.682244 -0.831342)
			(end -0.809244 -0.831342)
			(stroke
				(width 0.254)
				(type default)
			)
			(fill no)
			(layer "F.SilkS")
		)
		(fp_rect
			(start 4.8006 4.5593)
			(end 0.4064 -0.7493)
			(stroke
				(width 0)
				(type default)
			)
			(fill no)
			(layer "F.CrtYd")
		)
		(fp_line
			(start 4.8006 4.5593)
			(end 0.4064 4.5593)
			(stroke
				(width 0.1)
				(type default)
			)
			(layer "F.Fab")
		)
		(fp_line
			(start 4.8006 -0.7493)
			(end 4.8006 4.5593)
			(stroke
				(width 0.1)
				(type default)
			)
			(layer "F.Fab")
		)
		(fp_line
			(start 0.4064 4.5593)
			(end 0.4064 -0.7493)
			(stroke
				(width 0.1)
				(type default)
			)
			(layer "F.Fab")
		)
		(fp_line
			(start 0.4064 -0.7493)
			(end 4.8006 -0.7493)
			(stroke
				(width 0.1)
				(type default)
			)
			(layer "F.Fab")
		)
		(fp_circle
			(center -1.076706 -0.704342)
			(end -1.203706 -0.704342)
			(stroke
				(width 0.635)
				(type default)
			)
			(fill no)
			(layer "F.Fab")
		)
		(pad "1" smd rect
			(at 0 0 180)
			(size 1.651 0.508)
			(layers "F.Cu" "F.Mask" "F.Paste")
			(net "P12V_STBY")
		)
		(pad "2" smd rect
			(at 0 1.27 180)
			(size 1.651 0.508)
			(layers "F.Cu" "F.Mask" "F.Paste")
			(net "P12V_STBY")
		)
		(pad "3" smd rect
			(at 0 2.54 180)
			(size 1.651 0.508)
			(layers "F.Cu" "F.Mask" "F.Paste")
			(net "P12V_STBY")
		)
		(pad "4" smd rect
			(at 0 3.81 180)
			(size 1.651 0.508)
			(layers "F.Cu" "F.Mask" "F.Paste")
			(net "A_HSC_GATE3_R")
		)
		(pad "5" smd custom
			(at 3.937 1.905 180)
			(size 1.04775 1.04775)
			(layers "F.Cu" "F.Mask" "F.Paste")
			(net "P12V_MB0_SW")
			(options
				(clearance outline)
				(anchor circle)
			)
			(primitives
				(gr_poly
					(pts
						(xy -2.0955 -1.651) (xy -2.0955 1.651) (xy 0.4445 1.651) (xy 0.4445 2.2098) (xy 2.0955 2.2098)
						(xy 2.0955 -2.2098) (xy 0.4445 -2.2098) (xy 0.4445 -1.651)
					)
					(width 0)
					(fill yes)
				)
			)
		)
	)
	(footprint ""
		(layer "F.Cu")
		(at 159.87522 -125.1077 90)
		(property "Reference" "C3B5"
			(at 0 0 90)
			(layer "F.SilkS")
			(hide yes)
			(effects
				(font
					(size 1.27 1.27)
				)
			)
		)
		(property "Value" ""
			(at 0 0 90)
			(layer "F.Fab")
			(effects
				(font
					(size 1.27 1.27)
				)
			)
		)
		(duplicate_pad_numbers_are_jumpers no)
		(fp_poly
			(pts
				(xy 0.3048 -0.1016) (xy 0.3048 0.9906) (xy -0.3048 0.9906) (xy -0.3048 -0.1016)
			)
			(stroke
				(width 0)
				(type default)
			)
			(fill no)
			(layer "F.CrtYd")
		)
		(fp_line
			(start 0.3048 -0.1016)
			(end -0.3048 -0.1016)
			(stroke
				(width 0.1)
				(type default)
			)
			(layer "F.Fab")
		)
		(fp_line
			(start -0.3048 -0.1016)
			(end -0.3048 0.9906)
			(stroke
				(width 0.1)
				(type default)
			)
			(layer "F.Fab")
		)
		(fp_line
			(start 0.3048 0.9906)
			(end 0.3048 -0.1016)
			(stroke
				(width 0.1)
				(type default)
			)
			(layer "F.Fab")
		)
		(fp_line
			(start -0.3048 0.9906)
			(end 0.3048 0.9906)
			(stroke
				(width 0.1)
				(type default)
			)
			(layer "F.Fab")
		)
		(pad "1" smd rect
			(at 0 0 90)
			(size 0.508 0.508)
			(layers "F.Cu" "F.Mask" "F.Paste")
			(net "PVPP_KLM")
		)
		(pad "2" smd rect
			(at 0 0.889 90)
			(size 0.508 0.508)
			(layers "F.Cu" "F.Mask" "F.Paste")
			(net "GND")
		)
		(zone
			(layer "F.Cu")
			(hatch none 0.5)
			(connect_pads
				(clearance 0)
			)
			(min_thickness 0.25)
			(keepout
				(tracks allowed)
				(vias not_allowed)
				(pads allowed)
				(copperpour not_allowed)
				(footprints allowed)
			)
			(placement
				(enabled no)
				(sheetname "")
			)
			(fill
				(thermal_gap 0.5)
				(thermal_bridge_width 0.5)
				(island_removal_mode 0)
			)
			(polygon
				(pts
					(xy 160.12922 -124.8537) (xy 160.12922 -125.3617) (xy 160.51022 -125.3617) (xy 160.51022 -124.8537)
				)
			)
		)
		(zone
			(layer "F.Cu")
			(hatch none 0.5)
			(connect_pads
				(clearance 0)
			)
			(min_thickness 0.25)
			(keepout
				(tracks not_allowed)
				(vias allowed)
				(pads allowed)
				(copperpour not_allowed)
				(footprints allowed)
			)
			(placement
				(enabled no)
				(sheetname "")
			)
			(fill
				(thermal_gap 0.5)
				(thermal_bridge_width 0.5)
				(island_removal_mode 0)
			)
			(polygon
				(pts
					(xy 160.51022 -124.8537) (xy 160.51022 -125.3617) (xy 160.12922 -125.3617) (xy 160.12922 -124.8537)
				)
			)
		)
	)
	(footprint ""
		(layer "F.Cu")
		(at 149.7711 -31.1658)
		(property "Reference" "Y3F1"
			(at -0.0381 -2.08153 0)
			(unlocked yes)
			(layer "F.SilkS")
			(effects
				(font
					(size 0.7874 0.5842)
					(thickness 0.1524)
				)
				(justify left)
			)
		)
		(property "Value" ""
			(at 0 0 0)
			(layer "F.Fab")
			(effects
				(font
					(size 1.27 1.27)
				)
			)
		)
		(duplicate_pad_numbers_are_jumpers no)
		(fp_line
			(start -0.366522 -1.329944)
			(end 3.033522 -1.329944)
			(stroke
				(width 0.1524)
				(type default)
			)
			(layer "F.SilkS")
		)
		(fp_line
			(start -0.366522 -0.80391)
			(end -0.366522 -1.329944)
			(stroke
				(width 0.1524)
				(type default)
			)
			(layer "F.SilkS")
		)
		(fp_line
			(start -0.366522 3.869944)
			(end -0.366522 3.363468)
			(stroke
				(width 0.1524)
				(type default)
			)
			(layer "F.SilkS")
		)
		(fp_line
			(start 3.033522 -1.329944)
			(end 3.033522 -0.790956)
			(stroke
				(width 0.1524)
				(type default)
			)
			(layer "F.SilkS")
		)
		(fp_line
			(start 3.033522 3.370072)
			(end 3.033522 3.869944)
			(stroke
				(width 0.1524)
				(type default)
			)
			(layer "F.SilkS")
		)
		(fp_line
			(start 3.033522 3.869944)
			(end -0.366522 3.869944)
			(stroke
				(width 0.1524)
				(type default)
			)
			(layer "F.SilkS")
		)
		(fp_circle
			(center -1.914906 -0.701802)
			(end -1.787906 -0.701802)
			(stroke
				(width 0.254)
				(type default)
			)
			(fill no)
			(layer "F.SilkS")
		)
		(fp_rect
			(start -0.366522 3.869944)
			(end 3.033522 -1.329944)
			(stroke
				(width 0)
				(type default)
			)
			(fill no)
			(layer "F.CrtYd")
		)
		(fp_line
			(start -0.366522 -1.329944)
			(end 3.033522 -1.329944)
			(stroke
				(width 0.1)
				(type default)
			)
			(layer "F.Fab")
		)
		(fp_line
			(start -0.366522 3.869944)
			(end -0.366522 -1.329944)
			(stroke
				(width 0.1)
				(type default)
			)
			(layer "F.Fab")
		)
		(fp_line
			(start 3.033522 -1.329944)
			(end 3.033522 3.869944)
			(stroke
				(width 0.1)
				(type default)
			)
			(layer "F.Fab")
		)
		(fp_line
			(start 3.033522 3.869944)
			(end -0.366522 3.869944)
			(stroke
				(width 0.1)
				(type default)
			)
			(layer "F.Fab")
		)
		(fp_circle
			(center -1.913636 -0.708152)
			(end -1.786636 -0.708152)
			(stroke
				(width 0.254)
				(type default)
			)
			(fill no)
			(layer "F.Fab")
		)
		(pad "1" smd rect
			(at 0 0)
			(size 1.651 0.8382)
			(layers "F.Cu" "F.Mask" "F.Paste")
			(net "FM_CPU1_STL_BRD_OSC_EN")
		)
		(pad "2" smd rect
			(at 0 1.27)
			(size 1.651 0.8382)
			(layers "F.Cu" "F.Mask" "F.Paste")
			(net "NC_CLK_156M_CPU1_OSC")
		)
		(pad "3" smd rect
			(at 0 2.54)
			(size 1.651 0.8382)
			(layers "F.Cu" "F.Mask" "F.Paste")
			(net "GND")
		)
		(pad "4" smd rect
			(at 2.667 2.54)
			(size 1.651 0.8382)
			(layers "F.Cu" "F.Mask" "F.Paste")
			(net "CLK_156M_OSC_BRD_CPU1_DP")
		)
		(pad "5" smd rect
			(at 2.667 1.27)
			(size 1.651 0.8382)
			(layers "F.Cu" "F.Mask" "F.Paste")
			(net "CLK_156M_OSC_BRD_CPU1_DN")
		)
		(pad "6" smd rect
			(at 2.667 0)
			(size 1.651 0.8382)
			(layers "F.Cu" "F.Mask" "F.Paste")
			(net "P3V3")
		)
	)
)
